G04 ================== begin FILE IDENTIFICATION RECORD ==================*
G04 Layout Name:  D:/<user>/Wistron_project/16369-sd/gbr/16369-sd.brd*
G04 Film Name:    BMASK*
G04 File Format:  Gerber RS274X*
G04 File Origin:  Cadence Allegro 16.5-S056*
G04 Origin Date:  Wed Mar 29 13:12:41 2017*
G04 *
G04 Layer:  VIA CLASS/SOLDERMASK_BOTTOM*
G04 Layer:  PIN/SOLDERMASK_BOTTOM*
G04 Layer:  PACKAGE GEOMETRY/SOLDERMASK_BOTTOM*
G04 Layer:  DRAWING FORMAT/LAYER_PCB_STORY*
G04 Layer:  DRAWING FORMAT/LAYER_SOLDER_B*
G04 Layer:  BOARD GEOMETRY/SOLDERMASK_BOTTOM*
G04 *
G04 Offset:    (0.00 0.00)*
G04 Mirror:    No*
G04 Mode:      Positive*
G04 Rotation:  0*
G04 FullContactRelief:  No*
G04 UndefLineWidth:     6.00*
G04 ================== end FILE IDENTIFICATION RECORD ====================*
%FSLAX35Y35*MOIN*%
%IR0*IPPOS*OFA0.00000B0.00000*MIA0B0*SFA1.00000B1.00000*%
%ADD16C,.02*%
%ADD14C,.042*%
%ADD12C,.052*%
%ADD11C,.08*%
%ADD13C,.046*%
%ADD10C,.086*%
%ADD15C,.107*%
%ADD17C,.238*%
%ADD18C,.006*%
G75*
%LPD*%
G75*
G54D10*
X-18898Y16741D03*
X-17506Y723144D03*
X13800Y60400D03*
X114497Y137176D03*
X115583Y329366D03*
X114497Y525759D03*
X115583Y717948D03*
X218800Y337200D03*
X365520Y-1413D03*
X366606Y190776D03*
X365520Y387169D03*
X366606Y579359D03*
X494816Y713716D03*
G54D11*
X-5631Y5915D03*
X-4866Y709193D03*
X12000Y342400D03*
X222000Y8200D03*
X180200Y342500D03*
X489553Y2518D03*
G54D12*
X41752Y5118D03*
X22440Y303149D03*
X32283D03*
X42126D03*
X22440Y322835D03*
X32283D03*
X42126D03*
X190926Y5118D03*
X182677Y303149D03*
X192520D03*
X202363D03*
X182677Y322835D03*
X192520D03*
X202363D03*
G54D13*
X37283Y173228D03*
X27283D03*
X193583D03*
X183583D03*
G54D14*
X38189Y220472D03*
X28346Y222440D03*
X38189Y251968D03*
Y244094D03*
Y236220D03*
Y228346D03*
X28346Y232283D03*
Y240157D03*
Y250000D03*
X12598Y312992D03*
X51968D03*
X198426Y220472D03*
X188583Y222440D03*
X198426Y251968D03*
Y244094D03*
Y236220D03*
Y228346D03*
X188583Y232283D03*
Y240157D03*
Y250000D03*
X172835Y312992D03*
X212205D03*
G54D15*
X40157Y211023D03*
X24409D03*
X40157Y261417D03*
X24409D03*
X200394Y211023D03*
X184646D03*
X200394Y261417D03*
X184646D03*
G54D16*
G01X-351984Y-328833D02*
X-383984D01*
G01X-351984Y-344833D02*
Y-424833D01*
G01D02*
X998716D01*
G01X-355984Y-328833D02*
G02I-12000J0D01*
G01X-361134D02*
G02I-6850J0D01*
G01X-367984Y-344833D02*
Y-312833D01*
G01X-351984Y-344833D02*
X998716D01*
G01X-351984Y-380333D02*
X998716D01*
G01X211216Y-344833D02*
Y-424833D01*
G01X348716Y-344833D02*
Y-424833D01*
G01X463716Y-344833D02*
Y-424833D01*
G01X631216Y-344833D02*
Y-424833D01*
G01X801216Y-344833D02*
Y-424833D01*
G01X998716Y-344833D02*
Y-424833D01*
G01X1026716Y-328833D02*
G02I-12000J0D01*
G01X1021566D02*
G02I-6850J0D01*
G01X1014716Y-344833D02*
Y-312833D01*
G01X1030716Y-328833D02*
X998716D01*
X16977Y244294D03*
X16984Y248748D03*
X96200Y16400D03*
X133200Y17751D03*
X107506Y16719D03*
X116430Y16569D03*
X191391Y278906D03*
X195939Y278959D03*
G54D17*
X116339Y78740D03*
G54D18*
G01X-322688Y-405500D02*
X-321814Y-404625D01*
X-321159Y-403167D01*
X-320722Y-401124D01*
X-321159Y-399375D01*
X-322032Y-398208D01*
X-323561Y-397333D01*
X-329456D01*
Y-414833D01*
X-322251D01*
X-320722Y-413667D01*
X-319849Y-411916D01*
X-319412Y-409875D01*
X-319849Y-407833D01*
X-321159Y-406083D01*
X-322688Y-405500D01*
X-329456D01*
G01X-309991Y-414833D02*
Y-403167D01*
G01Y-405500D02*
X-308899Y-404333D01*
X-307807Y-403458D01*
X-306279Y-403167D01*
X-305188Y-403458D01*
X-303877Y-404333D01*
G01X-294019Y-420083D02*
X-292709Y-420666D01*
X-290962Y-420083D01*
X-289871Y-418917D01*
X-288997Y-417458D01*
X-287688Y-412792D01*
X-284849Y-403167D01*
G01X-291836D02*
X-287688Y-412792D01*
G01X-268441Y-404625D02*
X-269969Y-403458D01*
X-271279Y-403167D01*
X-273026Y-403750D01*
X-274336Y-404916D01*
X-275209Y-406958D01*
X-275428Y-409000D01*
X-275209Y-411042D01*
X-274336Y-412792D01*
X-273026Y-414250D01*
X-271279Y-414833D01*
X-269751Y-414250D01*
X-268441Y-413083D01*
G01X-257709Y-406958D02*
X-250722D01*
X-251377Y-404916D01*
X-252469Y-403750D01*
X-253997Y-403167D01*
X-255526Y-403458D01*
X-256836Y-404333D01*
X-257709Y-406375D01*
X-258146Y-408125D01*
Y-409875D01*
X-257709Y-411625D01*
X-256617Y-413375D01*
X-255307Y-414541D01*
X-253779Y-414833D01*
X-252251Y-414250D01*
X-250722Y-412500D01*
G01X-214631Y-398792D02*
X-215941Y-397916D01*
X-217469Y-397333D01*
X-219216D01*
X-221181Y-398208D01*
X-222709Y-399666D01*
X-223801Y-401417D01*
X-224674Y-404333D01*
X-224893Y-406958D01*
X-224456Y-409583D01*
X-223801Y-411333D01*
X-222491Y-413083D01*
X-220962Y-414250D01*
X-219434Y-414833D01*
X-217906D01*
X-216377Y-414250D01*
X-215067Y-413375D01*
X-213975Y-412209D01*
G01X-198004Y-414833D02*
Y-403167D01*
G01Y-405208D02*
X-198877Y-404042D01*
X-200188Y-403458D01*
X-201716Y-403167D01*
X-203244Y-403750D01*
X-204554Y-404916D01*
X-205428Y-406666D01*
X-205864Y-409000D01*
X-205428Y-411333D01*
X-204554Y-413083D01*
X-203244Y-414250D01*
X-201716Y-414833D01*
X-200188Y-414541D01*
X-198877Y-413667D01*
X-198004Y-412500D01*
G01X-188146Y-414833D02*
Y-403167D01*
G01Y-406083D02*
X-187272Y-404625D01*
X-185962Y-403458D01*
X-184216Y-403167D01*
X-182688Y-403458D01*
X-181377Y-404625D01*
X-180722Y-406666D01*
Y-414833D01*
G01X-171519Y-420083D02*
X-170209Y-420666D01*
X-168462Y-420083D01*
X-167371Y-418917D01*
X-166497Y-417458D01*
X-165188Y-412792D01*
X-162349Y-403167D01*
G01X-169336D02*
X-165188Y-412792D01*
G01X-149434Y-414833D02*
X-150744Y-414541D01*
X-152054Y-413375D01*
X-152928Y-411333D01*
X-153364Y-409000D01*
X-152928Y-406666D01*
X-152054Y-404625D01*
X-150744Y-403458D01*
X-149434Y-403167D01*
X-148124Y-403458D01*
X-146814Y-404625D01*
X-145941Y-406666D01*
X-145722Y-409000D01*
X-145941Y-411333D01*
X-146814Y-413375D01*
X-148124Y-414541D01*
X-149434Y-414833D01*
G01X-135646D02*
Y-403167D01*
G01Y-406083D02*
X-134772Y-404625D01*
X-133462Y-403458D01*
X-131716Y-403167D01*
X-130188Y-403458D01*
X-128877Y-404625D01*
X-128222Y-406666D01*
Y-414833D01*
G01X-101082D02*
Y-397333D01*
X-92786D01*
G01X-95842Y-405791D02*
X-101082D01*
G01X-82491Y-414833D02*
Y-403167D01*
G01Y-405500D02*
X-81399Y-404333D01*
X-80307Y-403458D01*
X-78779Y-403167D01*
X-77688Y-403458D01*
X-76377Y-404333D01*
G01X-61934Y-414833D02*
X-63244Y-414541D01*
X-64554Y-413375D01*
X-65428Y-411333D01*
X-65864Y-409000D01*
X-65428Y-406666D01*
X-64554Y-404625D01*
X-63244Y-403458D01*
X-61934Y-403167D01*
X-60624Y-403458D01*
X-59314Y-404625D01*
X-58441Y-406666D01*
X-58222Y-409000D01*
X-58441Y-411333D01*
X-59314Y-413375D01*
X-60624Y-414541D01*
X-61934Y-414833D01*
G01X-48146D02*
Y-403167D01*
G01Y-406083D02*
X-47272Y-404625D01*
X-45962Y-403458D01*
X-44216Y-403167D01*
X-42688Y-403458D01*
X-41377Y-404625D01*
X-40722Y-406666D01*
Y-414833D01*
G01X-26934Y-397333D02*
Y-414833D01*
G01X-29991Y-403167D02*
X-23877D01*
G01X3699Y-414833D02*
Y-397333D01*
X8939D01*
X10686Y-398208D01*
X11996Y-400250D01*
X12433Y-402583D01*
X11996Y-404916D01*
X10904Y-406666D01*
X8939Y-407542D01*
X3699D01*
G01X29496Y-414833D02*
Y-403167D01*
G01Y-405208D02*
X28623Y-404042D01*
X27312Y-403458D01*
X25784Y-403167D01*
X24256Y-403750D01*
X22946Y-404916D01*
X22072Y-406666D01*
X21636Y-409000D01*
X22072Y-411333D01*
X22946Y-413083D01*
X24256Y-414250D01*
X25784Y-414833D01*
X27312Y-414541D01*
X28623Y-413667D01*
X29496Y-412500D01*
G01X39354Y-414833D02*
Y-403167D01*
G01Y-406083D02*
X40228Y-404625D01*
X41538Y-403458D01*
X43284Y-403167D01*
X44812Y-403458D01*
X46123Y-404625D01*
X46778Y-406666D01*
Y-414833D01*
G01X57291Y-406958D02*
X64278D01*
X63623Y-404916D01*
X62531Y-403750D01*
X61003Y-403167D01*
X59474Y-403458D01*
X58164Y-404333D01*
X57291Y-406375D01*
X56854Y-408125D01*
Y-409875D01*
X57291Y-411625D01*
X58383Y-413375D01*
X59693Y-414541D01*
X61221Y-414833D01*
X62749Y-414250D01*
X64278Y-412500D01*
G01X78066Y-414833D02*
Y-397333D01*
G01X114812Y-405500D02*
X115686Y-404625D01*
X116341Y-403167D01*
X116778Y-401124D01*
X116341Y-399375D01*
X115468Y-398208D01*
X113939Y-397333D01*
X108044D01*
Y-414833D01*
X115249D01*
X116778Y-413667D01*
X117651Y-411916D01*
X118088Y-409875D01*
X117651Y-407833D01*
X116341Y-406083D01*
X114812Y-405500D01*
X108044D01*
G01X130566Y-414833D02*
X129256Y-414541D01*
X127946Y-413375D01*
X127072Y-411333D01*
X126636Y-409000D01*
X127072Y-406666D01*
X127946Y-404625D01*
X129256Y-403458D01*
X130566Y-403167D01*
X131876Y-403458D01*
X133186Y-404625D01*
X134059Y-406666D01*
X134278Y-409000D01*
X134059Y-411333D01*
X133186Y-413375D01*
X131876Y-414541D01*
X130566Y-414833D01*
G01X151996D02*
Y-403167D01*
G01Y-405208D02*
X151123Y-404042D01*
X149812Y-403458D01*
X148284Y-403167D01*
X146756Y-403750D01*
X145446Y-404916D01*
X144572Y-406666D01*
X144136Y-409000D01*
X144572Y-411333D01*
X145446Y-413083D01*
X146756Y-414250D01*
X148284Y-414833D01*
X149812Y-414541D01*
X151123Y-413667D01*
X151996Y-412500D01*
G01X162509Y-414833D02*
Y-403167D01*
G01Y-405500D02*
X163601Y-404333D01*
X164693Y-403458D01*
X166221Y-403167D01*
X167312Y-403458D01*
X168623Y-404333D01*
G01X186996Y-397333D02*
Y-414833D01*
G01Y-412209D02*
X186123Y-413667D01*
X184812Y-414541D01*
X183284Y-414833D01*
X181538Y-414250D01*
X180228Y-412792D01*
X179354Y-411042D01*
X179136Y-409000D01*
X179354Y-406958D01*
X180228Y-405208D01*
X181538Y-403750D01*
X183284Y-403167D01*
X184812Y-403458D01*
X185904Y-404042D01*
X186996Y-405208D01*
G01X-111361Y-369833D02*
Y-352333D01*
X-105684Y-366916D01*
X-100007Y-352333D01*
Y-369833D01*
G01X-88184D02*
X-89494Y-369541D01*
X-90804Y-368375D01*
X-91678Y-366333D01*
X-92114Y-364000D01*
X-91678Y-361666D01*
X-90804Y-359625D01*
X-89494Y-358458D01*
X-88184Y-358167D01*
X-86874Y-358458D01*
X-85564Y-359625D01*
X-84691Y-361666D01*
X-84472Y-364000D01*
X-84691Y-366333D01*
X-85564Y-368375D01*
X-86874Y-369541D01*
X-88184Y-369833D01*
G01X-66754Y-352333D02*
Y-369833D01*
G01Y-367209D02*
X-67627Y-368667D01*
X-68938Y-369541D01*
X-70466Y-369833D01*
X-72212Y-369250D01*
X-73522Y-367792D01*
X-74396Y-366042D01*
X-74614Y-364000D01*
X-74396Y-361958D01*
X-73522Y-360208D01*
X-72212Y-358750D01*
X-70466Y-358167D01*
X-68938Y-358458D01*
X-67846Y-359042D01*
X-66754Y-360208D01*
G01X-56459Y-361958D02*
X-49472D01*
X-50127Y-359916D01*
X-51219Y-358750D01*
X-52747Y-358167D01*
X-54276Y-358458D01*
X-55586Y-359333D01*
X-56459Y-361375D01*
X-56896Y-363125D01*
Y-364875D01*
X-56459Y-366625D01*
X-55367Y-368375D01*
X-54057Y-369541D01*
X-52529Y-369833D01*
X-51001Y-369250D01*
X-49472Y-367500D01*
G01X-35684Y-369833D02*
Y-352333D01*
G01X244916Y-414833D02*
Y-397333D01*
X242296Y-400833D01*
G01Y-414833D02*
X247536D01*
G01X258268Y-407542D02*
X259796Y-405500D01*
X261106Y-404333D01*
X262853Y-403750D01*
X264381Y-404333D01*
X265473Y-405500D01*
X266346Y-407250D01*
X266564Y-409291D01*
X266346Y-411042D01*
X265473Y-412792D01*
X264162Y-414250D01*
X262634Y-414833D01*
X260888Y-414250D01*
X259359Y-412500D01*
X258486Y-409875D01*
X258268Y-406958D01*
X258704Y-403167D01*
X259359Y-401124D01*
X260451Y-399083D01*
X261979Y-397625D01*
X263508Y-397333D01*
X265036Y-397916D01*
X266128Y-399375D01*
G01X275113Y-411333D02*
X276422Y-413375D01*
X278169Y-414541D01*
X280134Y-414833D01*
X281881Y-414541D01*
X283628Y-413083D01*
X284719Y-411333D01*
X284938Y-409583D01*
X284501Y-407542D01*
X282973Y-406083D01*
X281444Y-405500D01*
X279479D01*
G01X281444D02*
X282754Y-404625D01*
X283846Y-403167D01*
X284283Y-401417D01*
X283846Y-399666D01*
X282754Y-398208D01*
X280789Y-397333D01*
X278824Y-397625D01*
X276859Y-398792D01*
G01X293268Y-407542D02*
X294796Y-405500D01*
X296106Y-404333D01*
X297853Y-403750D01*
X299381Y-404333D01*
X300473Y-405500D01*
X301346Y-407250D01*
X301564Y-409291D01*
X301346Y-411042D01*
X300473Y-412792D01*
X299162Y-414250D01*
X297634Y-414833D01*
X295888Y-414250D01*
X294359Y-412500D01*
X293486Y-409875D01*
X293268Y-406958D01*
X293704Y-403167D01*
X294359Y-401124D01*
X295451Y-399083D01*
X296979Y-397625D01*
X298508Y-397333D01*
X300036Y-397916D01*
X301128Y-399375D01*
G01X311204Y-412792D02*
X312733Y-414250D01*
X314479Y-414833D01*
X316226Y-414250D01*
X317754Y-412500D01*
X318846Y-409875D01*
X319283Y-407250D01*
Y-404042D01*
X318846Y-401417D01*
X317754Y-399083D01*
X316444Y-397916D01*
X314916Y-397333D01*
X313169Y-397916D01*
X311859Y-399083D01*
X310986Y-400833D01*
X310549Y-403167D01*
X310986Y-405208D01*
X312078Y-407250D01*
X313388Y-408417D01*
X314916Y-408708D01*
X316662Y-408125D01*
X317973Y-406666D01*
X319283Y-404042D01*
G01X231799Y-369833D02*
Y-352333D01*
X237039D01*
X238786Y-353208D01*
X240096Y-355250D01*
X240533Y-357583D01*
X240096Y-359916D01*
X239004Y-361666D01*
X237039Y-362542D01*
X231799D01*
G01X258469Y-353792D02*
X257159Y-352916D01*
X255631Y-352333D01*
X253884D01*
X251919Y-353208D01*
X250391Y-354666D01*
X249299Y-356417D01*
X248426Y-359333D01*
X248207Y-361958D01*
X248644Y-364583D01*
X249299Y-366333D01*
X250609Y-368083D01*
X252138Y-369250D01*
X253666Y-369833D01*
X255194D01*
X256723Y-369250D01*
X258033Y-368375D01*
X259125Y-367209D01*
G01X272912Y-360500D02*
X273786Y-359625D01*
X274441Y-358167D01*
X274878Y-356124D01*
X274441Y-354375D01*
X273568Y-353208D01*
X272039Y-352333D01*
X266144D01*
Y-369833D01*
X273349D01*
X274878Y-368667D01*
X275751Y-366916D01*
X276188Y-364875D01*
X275751Y-362833D01*
X274441Y-361083D01*
X272912Y-360500D01*
X266144D01*
G01X282116Y-375666D02*
X295216D01*
G01X301144Y-369833D02*
Y-352333D01*
X311188Y-369833D01*
Y-352333D01*
G01X323666Y-369833D02*
X321919Y-369541D01*
X320391Y-368375D01*
X319081Y-366625D01*
X318207Y-364583D01*
X317771Y-362250D01*
Y-359916D01*
X318207Y-357583D01*
X319081Y-355541D01*
X320391Y-353792D01*
X321919Y-352625D01*
X323666Y-352333D01*
X325412Y-352625D01*
X326941Y-353792D01*
X328251Y-355541D01*
X329125Y-357583D01*
X329561Y-359916D01*
Y-362250D01*
X329125Y-364583D01*
X328251Y-366625D01*
X326941Y-368375D01*
X325412Y-369541D01*
X323666Y-369833D01*
G01X374507Y-352333D02*
X379966Y-369833D01*
X385425Y-352333D01*
G01X401833Y-369833D02*
X393099D01*
Y-352333D01*
X401833D01*
G01X398339Y-360791D02*
X393099D01*
G01X410599Y-369833D02*
Y-352333D01*
X416058D01*
X417804Y-353208D01*
X418896Y-354375D01*
X419333Y-356708D01*
X418896Y-359042D01*
X417586Y-360500D01*
X416058Y-361375D01*
X410599D01*
G01X416058D02*
X419333Y-369833D01*
G01X432466Y-370416D02*
X432029Y-370125D01*
Y-369541D01*
X432466Y-369250D01*
X432903Y-369541D01*
Y-370125D01*
X432466Y-370416D01*
G01X392881Y-412500D02*
X394628Y-413958D01*
X396593Y-414833D01*
X398339D01*
X400086Y-413958D01*
X401396Y-412500D01*
X402051Y-410458D01*
X401614Y-408417D01*
X400523Y-406666D01*
X398558Y-405500D01*
X395938Y-404916D01*
X394409Y-403750D01*
X393754Y-401708D01*
X394191Y-399666D01*
X395283Y-398208D01*
X396811Y-397333D01*
X398339D01*
X399868Y-397916D01*
X401178Y-399375D01*
G01X410163Y-414833D02*
Y-397333D01*
X414529D01*
X416276Y-398208D01*
X417586Y-399375D01*
X418678Y-401124D01*
X419551Y-403167D01*
X419769Y-406083D01*
X419551Y-409000D01*
X418678Y-411042D01*
X417586Y-412792D01*
X416276Y-413958D01*
X414529Y-414833D01*
X410163D01*
G01X580670Y-405500D02*
X579796Y-404625D01*
X579141Y-403167D01*
X578704Y-401124D01*
X579141Y-399375D01*
X580014Y-398208D01*
X581543Y-397333D01*
X587438D01*
Y-414833D01*
X580233D01*
X578704Y-413667D01*
X577831Y-411916D01*
X577394Y-409875D01*
X577831Y-407833D01*
X579141Y-406083D01*
X580670Y-405500D01*
X587438D01*
G01X570593Y-414833D02*
Y-397333D01*
X564916Y-411916D01*
X559239Y-397333D01*
Y-414833D01*
G01X552875D02*
X547416Y-397333D01*
X541957Y-414833D01*
G01X543923Y-408708D02*
X550910D01*
G01X534501Y-412500D02*
X532754Y-413958D01*
X530789Y-414833D01*
X529043D01*
X527296Y-413958D01*
X525986Y-412500D01*
X525331Y-410458D01*
X525768Y-408417D01*
X526859Y-406666D01*
X528824Y-405500D01*
X531444Y-404916D01*
X532973Y-403750D01*
X533628Y-401708D01*
X533191Y-399666D01*
X532099Y-398208D01*
X530571Y-397333D01*
X529043D01*
X527514Y-397916D01*
X526204Y-399375D01*
G01X517219Y-414833D02*
Y-397333D01*
G01X508923D02*
X517219Y-408125D01*
G01X507613Y-414833D02*
X513508Y-403167D01*
G01X508049Y-352333D02*
Y-369833D01*
X516783D01*
G01X533846D02*
Y-358167D01*
G01Y-360208D02*
X532973Y-359042D01*
X531662Y-358458D01*
X530134Y-358167D01*
X528606Y-358750D01*
X527296Y-359916D01*
X526422Y-361666D01*
X525986Y-364000D01*
X526422Y-366333D01*
X527296Y-368083D01*
X528606Y-369250D01*
X530134Y-369833D01*
X531662Y-369541D01*
X532973Y-368667D01*
X533846Y-367500D01*
G01X542831Y-375083D02*
X544141Y-375666D01*
X545888Y-375083D01*
X546979Y-373917D01*
X547853Y-372458D01*
X549162Y-367792D01*
X552001Y-358167D01*
G01X545014D02*
X549162Y-367792D01*
G01X561641Y-361958D02*
X568628D01*
X567973Y-359916D01*
X566881Y-358750D01*
X565353Y-358167D01*
X563824Y-358458D01*
X562514Y-359333D01*
X561641Y-361375D01*
X561204Y-363125D01*
Y-364875D01*
X561641Y-366625D01*
X562733Y-368375D01*
X564043Y-369541D01*
X565571Y-369833D01*
X567099Y-369250D01*
X568628Y-367500D01*
G01X579359Y-369833D02*
Y-358167D01*
G01Y-360500D02*
X580451Y-359333D01*
X581543Y-358458D01*
X583071Y-358167D01*
X584162Y-358458D01*
X585473Y-359333D01*
G01X672466Y-414833D02*
X670719Y-414541D01*
X669191Y-413375D01*
X667881Y-411625D01*
X667007Y-409583D01*
X666571Y-407250D01*
Y-404916D01*
X667007Y-402583D01*
X667881Y-400541D01*
X669191Y-398792D01*
X670719Y-397625D01*
X672466Y-397333D01*
X674212Y-397625D01*
X675741Y-398792D01*
X677051Y-400541D01*
X677925Y-402583D01*
X678361Y-404916D01*
Y-407250D01*
X677925Y-409583D01*
X677051Y-411625D01*
X675741Y-413375D01*
X674212Y-414541D01*
X672466Y-414833D01*
G01X674212Y-410166D02*
X676833Y-414833D01*
G01X685163Y-397333D02*
Y-409875D01*
X686036Y-412500D01*
X687783Y-414250D01*
X689966Y-414833D01*
X692149Y-414250D01*
X693896Y-412500D01*
X694769Y-409875D01*
Y-397333D01*
G01X704846D02*
X710086D01*
G01X707466D02*
Y-414833D01*
G01X704846D02*
X710086D01*
G01X719944D02*
Y-397333D01*
X729988Y-414833D01*
Y-397333D01*
G01X747269Y-398792D02*
X745959Y-397916D01*
X744431Y-397333D01*
X742684D01*
X740719Y-398208D01*
X739191Y-399666D01*
X738099Y-401417D01*
X737226Y-404333D01*
X737007Y-406958D01*
X737444Y-409583D01*
X738099Y-411333D01*
X739409Y-413083D01*
X740938Y-414250D01*
X742466Y-414833D01*
X743994D01*
X745523Y-414250D01*
X746833Y-413375D01*
X747925Y-412209D01*
G01X759966Y-414833D02*
Y-406958D01*
X755599Y-397333D01*
G01X764333D02*
X759966Y-406958D01*
G01X650163Y-369833D02*
Y-352333D01*
X654529D01*
X656276Y-353208D01*
X657586Y-354375D01*
X658678Y-356124D01*
X659551Y-358167D01*
X659769Y-361083D01*
X659551Y-364000D01*
X658678Y-366042D01*
X657586Y-367792D01*
X656276Y-368958D01*
X654529Y-369833D01*
X650163D01*
G01X669191Y-361958D02*
X676178D01*
X675523Y-359916D01*
X674431Y-358750D01*
X672903Y-358167D01*
X671374Y-358458D01*
X670064Y-359333D01*
X669191Y-361375D01*
X668754Y-363125D01*
Y-364875D01*
X669191Y-366625D01*
X670283Y-368375D01*
X671593Y-369541D01*
X673121Y-369833D01*
X674649Y-369250D01*
X676178Y-367500D01*
G01X686691Y-367792D02*
X687783Y-368958D01*
X689311Y-369833D01*
X690621D01*
X691931Y-369250D01*
X692804Y-368375D01*
X693241Y-367209D01*
X693023Y-365458D01*
X692149Y-364583D01*
X688219Y-362833D01*
X687346Y-360791D01*
X687783Y-359333D01*
X688656Y-358458D01*
X689966Y-358167D01*
X691276Y-358458D01*
X692586Y-359333D01*
G01X707466Y-358167D02*
Y-369833D01*
G01Y-353500D02*
X707029Y-353208D01*
Y-352625D01*
X707466Y-352333D01*
X707903Y-352625D01*
Y-353208D01*
X707466Y-353500D01*
G01X721909Y-374208D02*
X723438Y-375375D01*
X725184Y-375666D01*
X726712Y-375375D01*
X728023Y-373917D01*
X728896Y-371875D01*
Y-358167D01*
G01Y-360500D02*
X728023Y-359333D01*
X726712Y-358458D01*
X725184Y-358167D01*
X723438Y-358750D01*
X722346Y-359916D01*
X721472Y-361958D01*
X721036Y-364000D01*
X721254Y-365750D01*
X722128Y-367792D01*
X723438Y-369250D01*
X725184Y-369833D01*
X726494Y-369541D01*
X728023Y-368375D01*
X728896Y-367209D01*
G01X738754Y-369833D02*
Y-358167D01*
G01Y-361083D02*
X739628Y-359625D01*
X740938Y-358458D01*
X742684Y-358167D01*
X744212Y-358458D01*
X745523Y-359625D01*
X746178Y-361666D01*
Y-369833D01*
G01X756691Y-361958D02*
X763678D01*
X763023Y-359916D01*
X761931Y-358750D01*
X760403Y-358167D01*
X758874Y-358458D01*
X757564Y-359333D01*
X756691Y-361375D01*
X756254Y-363125D01*
Y-364875D01*
X756691Y-366625D01*
X757783Y-368375D01*
X759093Y-369541D01*
X760621Y-369833D01*
X762149Y-369250D01*
X763678Y-367500D01*
G01X774409Y-369833D02*
Y-358167D01*
G01Y-360500D02*
X775501Y-359333D01*
X776593Y-358458D01*
X778121Y-358167D01*
X779212Y-358458D01*
X780523Y-359333D01*
G01X821166Y-397333D02*
X819419Y-397916D01*
X818109Y-399375D01*
X817236Y-401124D01*
X816581Y-403458D01*
X816363Y-406083D01*
X816581Y-408708D01*
X817236Y-411042D01*
X818109Y-412792D01*
X819419Y-414250D01*
X821166Y-414833D01*
X822912Y-414250D01*
X824223Y-412792D01*
X825096Y-411042D01*
X825751Y-408708D01*
X825969Y-406083D01*
X825751Y-403458D01*
X825096Y-401124D01*
X824223Y-399375D01*
X822912Y-397916D01*
X821166Y-397333D01*
G01X833863Y-411333D02*
X835172Y-413375D01*
X836919Y-414541D01*
X838884Y-414833D01*
X840631Y-414541D01*
X842378Y-413083D01*
X843469Y-411333D01*
X843688Y-409583D01*
X843251Y-407542D01*
X841723Y-406083D01*
X840194Y-405500D01*
X838229D01*
G01X840194D02*
X841504Y-404625D01*
X842596Y-403167D01*
X843033Y-401417D01*
X842596Y-399666D01*
X841504Y-398208D01*
X839539Y-397333D01*
X837574Y-397625D01*
X835609Y-398792D01*
G01X852236Y-415416D02*
X860096Y-397333D01*
G01X869518Y-400250D02*
X870828Y-398500D01*
X872356Y-397625D01*
X874103Y-397333D01*
X876286Y-397916D01*
X877814Y-399375D01*
X878251Y-401124D01*
X878033Y-402875D01*
X877159Y-404333D01*
X872793Y-407250D01*
X870828Y-409291D01*
X869518Y-412209D01*
X869081Y-414833D01*
X878251D01*
G01X887454Y-412792D02*
X888983Y-414250D01*
X890729Y-414833D01*
X892476Y-414250D01*
X894004Y-412500D01*
X895096Y-409875D01*
X895533Y-407250D01*
Y-404042D01*
X895096Y-401417D01*
X894004Y-399083D01*
X892694Y-397916D01*
X891166Y-397333D01*
X889419Y-397916D01*
X888109Y-399083D01*
X887236Y-400833D01*
X886799Y-403167D01*
X887236Y-405208D01*
X888328Y-407250D01*
X889638Y-408417D01*
X891166Y-408708D01*
X892912Y-408125D01*
X894223Y-406666D01*
X895533Y-404042D01*
G01X904736Y-415416D02*
X912596Y-397333D01*
G01X922018Y-400250D02*
X923328Y-398500D01*
X924856Y-397625D01*
X926603Y-397333D01*
X928786Y-397916D01*
X930314Y-399375D01*
X930751Y-401124D01*
X930533Y-402875D01*
X929659Y-404333D01*
X925293Y-407250D01*
X923328Y-409291D01*
X922018Y-412209D01*
X921581Y-414833D01*
X930751D01*
G01X943666Y-397333D02*
X941919Y-397916D01*
X940609Y-399375D01*
X939736Y-401124D01*
X939081Y-403458D01*
X938863Y-406083D01*
X939081Y-408708D01*
X939736Y-411042D01*
X940609Y-412792D01*
X941919Y-414250D01*
X943666Y-414833D01*
X945412Y-414250D01*
X946723Y-412792D01*
X947596Y-411042D01*
X948251Y-408708D01*
X948469Y-406083D01*
X948251Y-403458D01*
X947596Y-401124D01*
X946723Y-399375D01*
X945412Y-397916D01*
X943666Y-397333D01*
G01X961166Y-414833D02*
Y-397333D01*
X958546Y-400833D01*
G01Y-414833D02*
X963786D01*
G01X978229D02*
X978666Y-411042D01*
X979321Y-407833D01*
X980194Y-404916D01*
X981286Y-401708D01*
X983033Y-397333D01*
X974299D01*
G01X868863Y-369833D02*
Y-352333D01*
X873229D01*
X874976Y-353208D01*
X876286Y-354375D01*
X877378Y-356124D01*
X878251Y-358167D01*
X878469Y-361083D01*
X878251Y-364000D01*
X877378Y-366042D01*
X876286Y-367792D01*
X874976Y-368958D01*
X873229Y-369833D01*
X868863D01*
G01X895096D02*
Y-358167D01*
G01Y-360208D02*
X894223Y-359042D01*
X892912Y-358458D01*
X891384Y-358167D01*
X889856Y-358750D01*
X888546Y-359916D01*
X887672Y-361666D01*
X887236Y-364000D01*
X887672Y-366333D01*
X888546Y-368083D01*
X889856Y-369250D01*
X891384Y-369833D01*
X892912Y-369541D01*
X894223Y-368667D01*
X895096Y-367500D01*
G01X908666Y-352333D02*
Y-369833D01*
G01X905609Y-358167D02*
X911723D01*
G01X922891Y-361958D02*
X929878D01*
X929223Y-359916D01*
X928131Y-358750D01*
X926603Y-358167D01*
X925074Y-358458D01*
X923764Y-359333D01*
X922891Y-361375D01*
X922454Y-363125D01*
Y-364875D01*
X922891Y-366625D01*
X923983Y-368375D01*
X925293Y-369541D01*
X926821Y-369833D01*
X928349Y-369250D01*
X929878Y-367500D01*
M02*
